(kicad_pcb
	(version 20260206)
	(generator "pcbnew")
	(generator_version "10.0")
	(general
		(thickness 1.6)
		(legacy_teardrops no)
	)
	(paper "A4")
	(title_block
		(title "04192023_DAF0TMB3IC0_F0TG_MB_C_brd_V02_OCP.brd")
		(comment 1 "Grand Teton / footprints 4941-4944 of 8354")
	)
	(layers
		(0 "F.Cu" signal "TOP")
		(4 "In1.Cu" signal "GND")
		(6 "In2.Cu" signal "IN1")
		(8 "In3.Cu" signal "GND1")
		(10 "In4.Cu" signal "IN2")
		(12 "In5.Cu" signal "GND2")
		(14 "In6.Cu" signal "IN3")
		(16 "In7.Cu" signal "GND3")
		(18 "In8.Cu" signal "VCC")
		(20 "In9.Cu" signal "VCC1")
		(22 "In10.Cu" signal "GND4")
		(24 "In11.Cu" signal "IN4")
		(26 "In12.Cu" signal "GND5")
		(28 "In13.Cu" signal "IN5")
		(30 "In14.Cu" signal "GND6")
		(32 "In15.Cu" signal "IN6")
		(34 "In16.Cu" signal "GND7")
		(2 "B.Cu" signal "BOTTOM")
		(9 "F.Adhes" user "F.Adhesive")
		(11 "B.Adhes" user "B.Adhesive")
		(13 "F.Paste" user "Package Geometry/Pastemask Top")
		(15 "B.Paste" user "Package Geometry/Pastemask Bottom")
		(5 "F.SilkS" user "Ref Des/Silkscreen Top")
		(7 "B.SilkS" user "Ref Des/Silkscreen Bottom")
		(1 "F.Mask" user "Board Geometry/Soldermask Top")
		(3 "B.Mask" user "Board Geometry/Soldermask Bottom")
		(17 "Dwgs.User" user "User.Drawings")
		(19 "Cmts.User" user "User.Comments")
		(21 "Eco1.User" user "User.Eco1")
		(23 "Eco2.User" user "User.Eco2")
		(25 "Edge.Cuts" user "Board Geometry/Outline")
		(27 "Margin" user)
		(31 "F.CrtYd" user "Package Geometry/Place Bound Top")
		(29 "B.CrtYd" user "Package Geometry/Place Bound Bottom")
		(35 "F.Fab" user "Ref Des/Assembly Top")
		(33 "B.Fab" user "Ref Des/Assembly Bottom")
	)
	(footprint ""
		(layer "B.Cu")
		(at 247.264682 -336.846164 180)
		(property "Reference" "U22"
			(at -1.699768 -5.606796 0)
			(unlocked yes)
			(layer "B.SilkS")
			(effects
				(font
					(size 0.7874 0.5842)
					(thickness 0.1524)
				)
				(justify left mirror)
			)
		)
		(property "Value" ""
			(at 0 0 0)
			(layer "B.Fab")
			(effects
				(font
					(size 1.27 1.27)
				)
				(justify mirror)
			)
		)
		(duplicate_pad_numbers_are_jumpers no)
		(fp_line
			(start 1.8542 3.949954)
			(end -1.8542 3.949954)
			(stroke
				(width 0.1524)
				(type default)
			)
			(layer "B.SilkS")
		)
		(fp_line
			(start 1.8542 -3.949954)
			(end 1.8542 3.949954)
			(stroke
				(width 0.1524)
				(type default)
			)
			(layer "B.SilkS")
		)
		(fp_line
			(start 1.282954 -3.949954)
			(end 1.8542 -3.949954)
			(stroke
				(width 0.1524)
				(type default)
			)
			(layer "B.SilkS")
		)
		(fp_line
			(start 0 -2.667)
			(end 1.282954 -3.949954)
			(stroke
				(width 0.1524)
				(type default)
			)
			(layer "B.SilkS")
		)
		(fp_line
			(start -1.282954 -3.949954)
			(end 0 -2.667)
			(stroke
				(width 0.1524)
				(type default)
			)
			(layer "B.SilkS")
		)
		(fp_line
			(start -1.8542 3.949954)
			(end -1.8542 -3.949954)
			(stroke
				(width 0.1524)
				(type default)
			)
			(layer "B.SilkS")
		)
		(fp_line
			(start -1.8542 -3.949954)
			(end -1.282954 -3.949954)
			(stroke
				(width 0.1524)
				(type default)
			)
			(layer "B.SilkS")
		)
		(fp_poly
			(pts
				(xy 2.334514 -5.227066) (xy 3.348482 -5.29209) (xy 2.906522 -4.24561)
			)
			(stroke
				(width 0)
				(type default)
			)
			(fill yes)
			(layer "B.SilkS")
		)
		(fp_line
			(start 2.249932 3.949954)
			(end -2.249932 3.949954)
			(stroke
				(width 0.1)
				(type default)
			)
			(layer "B.Fab")
		)
		(fp_line
			(start 2.249932 -3.949954)
			(end 2.249932 3.949954)
			(stroke
				(width 0.1)
				(type default)
			)
			(layer "B.Fab")
		)
		(fp_line
			(start -2.249932 3.949954)
			(end -2.249932 -3.949954)
			(stroke
				(width 0.1)
				(type default)
			)
			(layer "B.Fab")
		)
		(fp_line
			(start -2.249932 -3.949954)
			(end 2.249932 -3.949954)
			(stroke
				(width 0.1)
				(type default)
			)
			(layer "B.Fab")
		)
		(fp_poly
			(pts
				(xy 4.8006 -4.08305) (xy 4.8006 -3.06705) (xy 3.7846 -3.57505)
			)
			(stroke
				(width 0)
				(type default)
			)
			(fill yes)
			(layer "B.Fab")
		)
		(pad "1" smd rect
			(at 2.800096 -3.57505 90)
			(size 0.3048 1.6002)
			(layers "B.Cu" "B.Mask" "B.Paste")
			(net "RT_ROM_SMB_MUX_ADDR0")
		)
		(pad "2" smd rect
			(at 2.800096 -2.925064 90)
			(size 0.3048 1.6002)
			(layers "B.Cu" "B.Mask" "B.Paste")
			(net "RT_ROM_SMB_MUX_ADDR1")
		)
		(pad "3" smd rect
			(at 2.800096 -2.275078 90)
			(size 0.3048 1.6002)
			(layers "B.Cu" "B.Mask" "B.Paste")
			(net "RST_SMB_RT_ROM_N")
		)
		(pad "4" smd rect
			(at 2.800096 -1.625092 90)
			(size 0.3048 1.6002)
			(layers "B.Cu" "B.Mask" "B.Paste")
			(net "SMB_RT_CPU1_P0_ROM_MUX_2D_R_SDA")
		)
		(pad "5" smd rect
			(at 2.800096 -0.975106 90)
			(size 0.3048 1.6002)
			(layers "B.Cu" "B.Mask" "B.Paste")
			(net "SMB_RT_CPU1_P0_ROM_MUX_2D_R_SCL")
		)
		(pad "6" smd rect
			(at 2.800096 -0.32512 90)
			(size 0.3048 1.6002)
			(layers "B.Cu" "B.Mask" "B.Paste")
			(net "SMB_RT_CPU1_P1_ROM_MUX_2D_R_SDA")
		)
		(pad "7" smd rect
			(at 2.800096 0.32512 90)
			(size 0.3048 1.6002)
			(layers "B.Cu" "B.Mask" "B.Paste")
			(net "SMB_RT_CPU1_P1_ROM_MUX_2D_R_SCL")
		)
		(pad "8" smd rect
			(at 2.800096 0.975106 90)
			(size 0.3048 1.6002)
			(layers "B.Cu" "B.Mask" "B.Paste")
			(net "SMB_RT_CPU1_P3_ROM_MUX_2D_R_SDA")
		)
		(pad "9" smd rect
			(at 2.800096 1.625092 90)
			(size 0.3048 1.6002)
			(layers "B.Cu" "B.Mask" "B.Paste")
			(net "SMB_RT_CPU1_P3_ROM_MUX_2D_R_SCL")
		)
		(pad "10" smd rect
			(at 2.800096 2.275078 90)
			(size 0.3048 1.6002)
			(layers "B.Cu" "B.Mask" "B.Paste")
			(net "SMB_RT_CPU1_P2_ROM_MUX_2D_R_SDA")
		)
		(pad "11" smd rect
			(at 2.800096 2.925064 90)
			(size 0.3048 1.6002)
			(layers "B.Cu" "B.Mask" "B.Paste")
			(net "SMB_RT_CPU1_P2_ROM_MUX_2D_R_SCL")
		)
		(pad "12" smd rect
			(at 2.800096 3.57505 90)
			(size 0.3048 1.6002)
			(layers "B.Cu" "B.Mask" "B.Paste")
			(net "GND")
		)
		(pad "13" smd rect
			(at -2.800096 3.57505 90)
			(size 0.3048 1.6002)
			(layers "B.Cu" "B.Mask" "B.Paste")
			(net "SMB_RT_CPU0_P0_ROM_MUX_2D_R_SDA")
		)
		(pad "14" smd rect
			(at -2.800096 2.925064 90)
			(size 0.3048 1.6002)
			(layers "B.Cu" "B.Mask" "B.Paste")
			(net "SMB_RT_CPU0_P0_ROM_MUX_2D_R_SCL")
		)
		(pad "15" smd rect
			(at -2.800096 2.275078 90)
			(size 0.3048 1.6002)
			(layers "B.Cu" "B.Mask" "B.Paste")
			(net "SMB_RT_CPU0_P1_ROM_MUX_2D_R_SDA")
		)
		(pad "16" smd rect
			(at -2.800096 1.625092 90)
			(size 0.3048 1.6002)
			(layers "B.Cu" "B.Mask" "B.Paste")
			(net "SMB_RT_CPU0_P1_ROM_MUX_2D_R_SCL")
		)
		(pad "17" smd rect
			(at -2.800096 0.975106 90)
			(size 0.3048 1.6002)
			(layers "B.Cu" "B.Mask" "B.Paste")
			(net "SMB_RT_CPU0_P3_ROM_MUX_2D_R_SDA")
		)
		(pad "18" smd rect
			(at -2.800096 0.32512 90)
			(size 0.3048 1.6002)
			(layers "B.Cu" "B.Mask" "B.Paste")
			(net "SMB_RT_CPU0_P3_ROM_MUX_2D_R_SCL")
		)
		(pad "19" smd rect
			(at -2.800096 -0.32512 90)
			(size 0.3048 1.6002)
			(layers "B.Cu" "B.Mask" "B.Paste")
			(net "SMB_RT_CPU0_P2_ROM_MUX_2D_R_SDA")
		)
		(pad "20" smd rect
			(at -2.800096 -0.975106 90)
			(size 0.3048 1.6002)
			(layers "B.Cu" "B.Mask" "B.Paste")
			(net "SMB_RT_CPU0_P2_ROM_MUX_2D_R_SCL")
		)
		(pad "21" smd rect
			(at -2.800096 -1.625092 90)
			(size 0.3048 1.6002)
			(layers "B.Cu" "B.Mask" "B.Paste")
			(net "RT_ROM_SMB_MUX_ADDR2")
		)
		(pad "22" smd rect
			(at -2.800096 -2.275078 90)
			(size 0.3048 1.6002)
			(layers "B.Cu" "B.Mask" "B.Paste")
			(net "SMB_MUX_RT_ROM_SCL")
		)
		(pad "23" smd rect
			(at -2.800096 -2.925064 90)
			(size 0.3048 1.6002)
			(layers "B.Cu" "B.Mask" "B.Paste")
			(net "SMB_MUX_RT_ROM_SDA")
		)
		(pad "24" smd rect
			(at -2.800096 -3.57505 90)
			(size 0.3048 1.6002)
			(layers "B.Cu" "B.Mask" "B.Paste")
			(net "P1V8_AUX")
		)
	)
	(footprint ""
		(layer "B.Cu")
		(at 285.299912 -420.350442 90)
		(property "Reference" "C2339"
			(at 0 0 90)
			(layer "B.SilkS")
			(hide yes)
			(effects
				(font
					(size 1.27 1.27)
				)
				(justify mirror)
			)
		)
		(property "Value" ""
			(at 0 0 90)
			(layer "B.Fab")
			(effects
				(font
					(size 1.27 1.27)
				)
				(justify mirror)
			)
		)
		(duplicate_pad_numbers_are_jumpers no)
		(fp_line
			(start 0.7874 -0.4064)
			(end -0.7874 -0.4064)
			(stroke
				(width 0.1524)
				(type default)
			)
			(layer "B.SilkS")
		)
		(fp_line
			(start -0.7874 -0.4064)
			(end -0.7874 0.4064)
			(stroke
				(width 0.1524)
				(type default)
			)
			(layer "B.SilkS")
		)
		(fp_line
			(start 0.7874 0.4064)
			(end 0.7874 -0.4064)
			(stroke
				(width 0.1524)
				(type default)
			)
			(layer "B.SilkS")
		)
		(fp_line
			(start -0.7874 0.4064)
			(end 0.7874 0.4064)
			(stroke
				(width 0.1524)
				(type default)
			)
			(layer "B.SilkS")
		)
		(fp_line
			(start 0.67945 -0.305054)
			(end 0.12065 -0.305054)
			(stroke
				(width 0.1)
				(type default)
			)
			(layer "B.Fab")
		)
		(fp_line
			(start 0.12065 -0.305054)
			(end 0.12065 -0.2794)
			(stroke
				(width 0.1)
				(type default)
			)
			(layer "B.Fab")
		)
		(fp_line
			(start -0.12065 -0.3048)
			(end -0.67945 -0.3048)
			(stroke
				(width 0.1)
				(type default)
			)
			(layer "B.Fab")
		)
		(fp_line
			(start -0.67945 -0.3048)
			(end -0.67945 0.3048)
			(stroke
				(width 0.1)
				(type default)
			)
			(layer "B.Fab")
		)
		(fp_line
			(start 0.12065 -0.2794)
			(end -0.12065 -0.2794)
			(stroke
				(width 0.1)
				(type default)
			)
			(layer "B.Fab")
		)
		(fp_line
			(start -0.12065 -0.2794)
			(end -0.12065 -0.3048)
			(stroke
				(width 0.1)
				(type default)
			)
			(layer "B.Fab")
		)
		(fp_line
			(start 0.12065 0.2794)
			(end 0.12065 0.3048)
			(stroke
				(width 0.1)
				(type default)
			)
			(layer "B.Fab")
		)
		(fp_line
			(start -0.120396 0.2794)
			(end 0.12065 0.2794)
			(stroke
				(width 0.1)
				(type default)
			)
			(layer "B.Fab")
		)
		(fp_line
			(start 0.67945 0.3048)
			(end 0.67945 -0.305054)
			(stroke
				(width 0.1)
				(type default)
			)
			(layer "B.Fab")
		)
		(fp_line
			(start 0.12065 0.3048)
			(end 0.67945 0.3048)
			(stroke
				(width 0.1)
				(type default)
			)
			(layer "B.Fab")
		)
		(fp_line
			(start -0.120396 0.3048)
			(end -0.120396 0.2794)
			(stroke
				(width 0.1)
				(type default)
			)
			(layer "B.Fab")
		)
		(fp_line
			(start -0.67945 0.3048)
			(end -0.120396 0.3048)
			(stroke
				(width 0.1)
				(type default)
			)
			(layer "B.Fab")
		)
		(pad "1" smd circle
			(at 0.40005 0 270)
			(size 0 0)
			(layers "B.Cu" "B.Mask" "B.Paste")
			(net "P3V3_9ZXL045_P0_VDD")
		)
		(pad "2" smd circle
			(at -0.40005 0 270)
			(size 0 0)
			(layers "B.Cu" "B.Mask" "B.Paste")
			(net "GND")
		)
	)
	(footprint ""
		(layer "B.Cu")
		(at 197.225158 -77.192632)
		(property "Reference" "U67"
			(at 2.032 -3.27533 0)
			(unlocked yes)
			(layer "B.SilkS")
			(effects
				(font
					(size 0.7874 0.5842)
					(thickness 0.1524)
				)
				(justify left mirror)
			)
		)
		(property "Value" ""
			(at 0 0 0)
			(layer "B.Fab")
			(effects
				(font
					(size 1.27 1.27)
				)
				(justify mirror)
			)
		)
		(duplicate_pad_numbers_are_jumpers no)
		(fp_line
			(start -2.0066 -2.5527)
			(end -2.0066 2.5527)
			(stroke
				(width 0.1524)
				(type default)
			)
			(layer "B.SilkS")
		)
		(fp_line
			(start -2.0066 2.5527)
			(end 2.0066 2.5527)
			(stroke
				(width 0.1524)
				(type default)
			)
			(layer "B.SilkS")
		)
		(fp_line
			(start -0.5715 -2.5527)
			(end -2.0066 -2.5527)
			(stroke
				(width 0.1524)
				(type default)
			)
			(layer "B.SilkS")
		)
		(fp_line
			(start 0 -1.9812)
			(end -0.5715 -2.5527)
			(stroke
				(width 0.1524)
				(type default)
			)
			(layer "B.SilkS")
		)
		(fp_line
			(start 0.5715 -2.5527)
			(end 0 -1.9812)
			(stroke
				(width 0.1524)
				(type default)
			)
			(layer "B.SilkS")
		)
		(fp_line
			(start 2.0066 -2.5527)
			(end 0.5715 -2.5527)
			(stroke
				(width 0.1524)
				(type default)
			)
			(layer "B.SilkS")
		)
		(fp_line
			(start 2.0066 2.5527)
			(end 2.0066 -2.5527)
			(stroke
				(width 0.1524)
				(type default)
			)
			(layer "B.SilkS")
		)
		(fp_poly
			(pts
				(xy 3.793236 -2.006092) (xy 4.346956 -2.33426) (xy 4.346956 -1.70942)
			)
			(stroke
				(width 0)
				(type default)
			)
			(fill yes)
			(layer "B.SilkS")
		)
		(fp_line
			(start -2.249932 -2.549906)
			(end -2.249932 2.549906)
			(stroke
				(width 0.1)
				(type default)
			)
			(layer "B.Fab")
		)
		(fp_line
			(start -2.249932 2.549906)
			(end 2.249932 2.549906)
			(stroke
				(width 0.1)
				(type default)
			)
			(layer "B.Fab")
		)
		(fp_line
			(start 2.249932 -2.549906)
			(end -2.249932 -2.549906)
			(stroke
				(width 0.1)
				(type default)
			)
			(layer "B.Fab")
		)
		(fp_line
			(start 2.249932 2.549906)
			(end 2.249932 -2.549906)
			(stroke
				(width 0.1)
				(type default)
			)
			(layer "B.Fab")
		)
		(fp_poly
			(pts
				(xy 4.36372 -1.608328) (xy 4.36372 -2.233168) (xy 3.81 -1.905)
			)
			(stroke
				(width 0)
				(type default)
			)
			(fill yes)
			(layer "B.Fab")
		)
		(pad "1" smd rect
			(at 2.921 -1.949958 270)
			(size 0.3556 1.4986)
			(layers "B.Cu" "B.Mask" "B.Paste")
			(net "FB_BMC_ISOLATE")
		)
		(pad "2" smd rect
			(at 2.921 -1.299972 270)
			(size 0.3556 1.4986)
			(layers "B.Cu" "B.Mask" "B.Paste")
			(net "NCSI_BMC_RXD1_R")
		)
		(pad "3" smd rect
			(at 2.921 -0.649986 270)
			(size 0.3556 1.4986)
			(layers "B.Cu" "B.Mask" "B.Paste")
			(net "NCSI_OCP_SFF_RXD1")
		)
		(pad "4" smd rect
			(at 2.921 0 270)
			(size 0.3556 1.4986)
			(layers "B.Cu" "B.Mask" "B.Paste")
			(net "FB_BMC_ISOLATE")
		)
		(pad "5" smd rect
			(at 2.921 0.649986 270)
			(size 0.3556 1.4986)
			(layers "B.Cu" "B.Mask" "B.Paste")
			(net "NCSI_BMC_RXD0_R")
		)
		(pad "6" smd rect
			(at 2.921 1.299972 270)
			(size 0.3556 1.4986)
			(layers "B.Cu" "B.Mask" "B.Paste")
			(net "NCSI_OCP_SFF_RXD0")
		)
		(pad "7" smd rect
			(at 2.921 1.949958 270)
			(size 0.3556 1.4986)
			(layers "B.Cu" "B.Mask" "B.Paste")
			(net "GND")
		)
		(pad "8" smd rect
			(at -2.921 1.949958 270)
			(size 0.3556 1.4986)
			(layers "B.Cu" "B.Mask" "B.Paste")
			(net "NCSI_OCP_SFF_CRS_DV")
		)
		(pad "9" smd rect
			(at -2.921 1.299972 270)
			(size 0.3556 1.4986)
			(layers "B.Cu" "B.Mask" "B.Paste")
			(net "NCSI_BMC_CRS_DV_R")
		)
		(pad "10" smd rect
			(at -2.921 0.649986 270)
			(size 0.3556 1.4986)
			(layers "B.Cu" "B.Mask" "B.Paste")
			(net "FB_BMC_ISOLATE")
		)
		(pad "11" smd rect
			(at -2.921 0 270)
			(size 0.3556 1.4986)
			(layers "B.Cu" "B.Mask" "B.Paste")
			(net "OCP_SFF_ISO1_RBT_ARB_IN")
		)
		(pad "12" smd rect
			(at -2.921 -0.649986 270)
			(size 0.3556 1.4986)
			(layers "B.Cu" "B.Mask" "B.Paste")
			(net "OCP_SFF_RBT_ARB_IN_R")
		)
		(pad "13" smd rect
			(at -2.921 -1.299972 270)
			(size 0.3556 1.4986)
			(layers "B.Cu" "B.Mask" "B.Paste")
			(net "FB_BMC_ISOLATE")
		)
		(pad "14" smd rect
			(at -2.921 -1.949958 270)
			(size 0.3556 1.4986)
			(layers "B.Cu" "B.Mask" "B.Paste")
			(net "P3V3_AUX")
		)
	)
	(footprint ""
		(layer "B.Cu")
		(at 74.940668 -388.846568)
		(property "Reference" "C324"
			(at 0 0 0)
			(layer "B.SilkS")
			(hide yes)
			(effects
				(font
					(size 1.27 1.27)
				)
				(justify mirror)
			)
		)
		(property "Value" ""
			(at 0 0 0)
			(layer "B.Fab")
			(effects
				(font
					(size 1.27 1.27)
				)
				(justify mirror)
			)
		)
		(duplicate_pad_numbers_are_jumpers no)
		(fp_line
			(start -1.524 -0.762)
			(end -1.524 0.762)
			(stroke
				(width 0.1524)
				(type default)
			)
			(layer "B.SilkS")
		)
		(fp_line
			(start -1.524 0.762)
			(end 1.524 0.762)
			(stroke
				(width 0.1524)
				(type default)
			)
			(layer "B.SilkS")
		)
		(fp_line
			(start 1.524 -0.762)
			(end -1.524 -0.762)
			(stroke
				(width 0.1524)
				(type default)
			)
			(layer "B.SilkS")
		)
		(fp_line
			(start 1.524 0.762)
			(end 1.524 -0.762)
			(stroke
				(width 0.1524)
				(type default)
			)
			(layer "B.SilkS")
		)
		(fp_line
			(start -1.1049 -0.724916)
			(end 1.1049 -0.724916)
			(stroke
				(width 0.1)
				(type default)
			)
			(layer "B.Fab")
		)
		(fp_line
			(start -1.1049 0.724916)
			(end -1.1049 -0.724916)
			(stroke
				(width 0.1)
				(type default)
			)
			(layer "B.Fab")
		)
		(fp_line
			(start 1.1049 -0.724916)
			(end 1.1049 0.724916)
			(stroke
				(width 0.1)
				(type default)
			)
			(layer "B.Fab")
		)
		(fp_line
			(start 1.1049 0.724916)
			(end -1.1049 0.724916)
			(stroke
				(width 0.1)
				(type default)
			)
			(layer "B.Fab")
		)
		(pad "1" smd rect
			(at 0.889 0)
			(size 1.016 1.27)
			(layers "B.Cu" "B.Mask" "B.Paste")
			(net "P0V9_CPU1_RT1_2A")
		)
		(pad "2" smd rect
			(at -0.889 0)
			(size 1.016 1.27)
			(layers "B.Cu" "B.Mask" "B.Paste")
			(net "GND")
		)
	)
)
